(kicad_pcb
	(version 20260206)
	(generator "pcbnew")
	(generator_version "10.0")
	(general
		(thickness 1.6)
		(legacy_teardrops no)
	)
	(paper "A4")
	(title_block
		(title "03242023_DA0F0TMBIJ0_F0T_Motherboard_J_brd_V01_OCP.brd")
		(comment 1 "Grand Teton / footprint 3039 of 6105 (U2), pads 1169-1274 of 4677")
	)
	(layers
		(0 "F.Cu" signal "TOP")
		(4 "In1.Cu" signal "GND")
		(6 "In2.Cu" signal "IN1")
		(8 "In3.Cu" signal "GND1")
		(10 "In4.Cu" signal "IN2")
		(12 "In5.Cu" signal "GND2")
		(14 "In6.Cu" signal "IN3")
		(16 "In7.Cu" signal "GND3")
		(18 "In8.Cu" signal "VCC")
		(20 "In9.Cu" signal "VCC1")
		(22 "In10.Cu" signal "GND4")
		(24 "In11.Cu" signal "IN4")
		(26 "In12.Cu" signal "GND5")
		(28 "In13.Cu" signal "IN5")
		(30 "In14.Cu" signal "GND6")
		(32 "In15.Cu" signal "IN6")
		(34 "In16.Cu" signal "GND7")
		(2 "B.Cu" signal "BOTTOM")
		(9 "F.Adhes" user "F.Adhesive")
		(11 "B.Adhes" user "B.Adhesive")
		(13 "F.Paste" user "Package Geometry/Pastemask Top")
		(15 "B.Paste" user "Package Geometry/Pastemask Bottom")
		(5 "F.SilkS" user "Ref Des/Silkscreen Top")
		(7 "B.SilkS" user "Ref Des/Silkscreen Bottom")
		(1 "F.Mask" user "Board Geometry/Soldermask Top")
		(3 "B.Mask" user "Board Geometry/Soldermask Bottom")
		(17 "Dwgs.User" user "User.Drawings")
		(19 "Cmts.User" user "User.Comments")
		(21 "Eco1.User" user "User.Eco1")
		(23 "Eco2.User" user "User.Eco2")
		(25 "Edge.Cuts" user "Board Geometry/Outline")
		(27 "Margin" user)
		(31 "F.CrtYd" user "Package Geometry/Place Bound Top")
		(29 "B.CrtYd" user "Package Geometry/Place Bound Bottom")
		(35 "F.Fab" user "Ref Des/Assembly Top")
		(33 "B.Fab" user "Ref Des/Assembly Bottom")
	)
	(footprint ""
		(layer "F.Cu")
		(at 359.870248 -251.76988 90)
		(property "Reference" "U2"
			(at -74.416158 -44.488608 0)
			(unlocked yes)
			(layer "F.SilkS")
			(effects
				(font
					(size 1.6002 1.1938)
					(thickness 0.1524)
				)
				(justify left)
			)
		)
		(property "Value" ""
			(at 0 0 90)
			(layer "F.Fab")
			(effects
				(font
					(size 1.27 1.27)
				)
			)
		)
		(duplicate_pad_numbers_are_jumpers no)
		(pad "BJ5" smd circle
			(at -34.169604 -4.518914 270)
			(size 0.4318 0.4318)
			(layers "F.Cu" "F.Mask" "F.Paste")
			(net "UPI_CPU1_CPU0_P1P0_DP<19>")
		)
		(pad "BJ7" smd circle
			(at -32.541718 -4.518914 270)
			(size 0.4318 0.4318)
			(layers "F.Cu" "F.Mask" "F.Paste")
			(net "PVCCD_HV_CPU0")
		)
		(pad "BJ9" smd circle
			(at -30.914086 -4.518914 270)
			(size 0.4318 0.4318)
			(layers "F.Cu" "F.Mask" "F.Paste")
			(net "P5E_CPU0_PE1_RX_DP<12>")
		)
		(pad "BJ11" smd circle
			(at -29.2862 -4.518914 270)
			(size 0.4318 0.4318)
			(layers "F.Cu" "F.Mask" "F.Paste")
			(net "PVCCD_HV_CPU0")
		)
		(pad "BJ13" smd circle
			(at -27.658314 -4.518914 270)
			(size 0.4318 0.4318)
			(layers "F.Cu" "F.Mask" "F.Paste")
			(net "P5E_CPU0_PE1_TX_DN<13>")
		)
		(pad "BJ15" smd circle
			(at -26.030682 -4.518914 270)
			(size 0.4318 0.4318)
			(layers "F.Cu" "F.Mask" "F.Paste")
			(net "PVCCINFAON_CPU0")
		)
		(pad "BJ17" smd circle
			(at -24.402796 -4.518914 270)
			(size 0.4318 0.4318)
			(layers "F.Cu" "F.Mask" "F.Paste")
			(net "DMI_CPU0_PCH_RX_C_DP<3>")
		)
		(pad "BJ19" smd circle
			(at -22.77491 -4.518914 270)
			(size 0.4318 0.4318)
			(layers "F.Cu" "F.Mask" "F.Paste")
			(net "PVNN_MAIN_CPU0")
		)
		(pad "BJ21" smd circle
			(at -21.147278 -4.518914 270)
			(size 0.4318 0.4318)
			(layers "F.Cu" "F.Mask" "F.Paste")
			(net "NC_CPU0_MDFI_DIE00_NS1")
		)
		(pad "BJ23" smd circle
			(at -19.519392 -4.518914 270)
			(size 0.4318 0.4318)
			(layers "F.Cu" "F.Mask" "F.Paste")
			(net "DBP_CPU0_HOOK8_MBP2_GTL_QS_R_N")
		)
		(pad "BJ25" smd circle
			(at -17.89176 -4.518914 270)
			(size 0.4318 0.4318)
			(layers "F.Cu" "F.Mask" "F.Paste")
			(net "SVID_ALERT1_CPU0_N")
		)
		(pad "BJ60" smd circle
			(at 12.19454 -4.408932 270)
			(size 0.4318 0.4318)
			(layers "F.Cu" "F.Mask" "F.Paste")
			(net "PVCCINFAON_CPU0")
		)
		(pad "BJ62" smd circle
			(at 13.822426 -4.408932 270)
			(size 0.4318 0.4318)
			(layers "F.Cu" "F.Mask" "F.Paste")
			(net "GND")
		)
		(pad "BJ64" smd circle
			(at 15.450058 -4.408932 270)
			(size 0.4318 0.4318)
			(layers "F.Cu" "F.Mask" "F.Paste")
			(net "TP_ESPI_IBL_CPU0_IO1_LVC1")
		)
		(pad "BJ66" smd circle
			(at 17.07769 -4.408932 270)
			(size 0.4318 0.4318)
			(layers "F.Cu" "F.Mask" "F.Paste")
			(net "TP_TRC_CPU0_PTI<28>")
		)
		(pad "BJ68" smd circle
			(at 18.705576 -4.408932 270)
			(size 0.4318 0.4318)
			(layers "F.Cu" "F.Mask" "F.Paste")
			(net "GND")
		)
		(pad "BJ70" smd circle
			(at 20.333462 -4.408932 270)
			(size 0.4318 0.4318)
			(layers "F.Cu" "F.Mask" "F.Paste")
			(net "NC_CPU0_VIEWPIN_DIE01<3>")
		)
		(pad "BJ72" smd circle
			(at 21.961094 -4.408932 270)
			(size 0.4318 0.4318)
			(layers "F.Cu" "F.Mask" "F.Paste")
			(net "PVCCFA_EHV_FIVRA_CPU0")
		)
		(pad "BJ74" smd circle
			(at 23.58898 -4.408932 270)
			(size 0.4318 0.4318)
			(layers "F.Cu" "F.Mask" "F.Paste")
			(net "UPI_CPU1_CPU0_P2P2_DN<3>")
		)
		(pad "BJ76" smd circle
			(at 25.216612 -4.408932 270)
			(size 0.4318 0.4318)
			(layers "F.Cu" "F.Mask" "F.Paste")
			(net "UPI_CPU1_CPU0_P2P2_DN<5>")
		)
		(pad "BJ78" smd circle
			(at 26.844498 -4.408932 270)
			(size 0.4318 0.4318)
			(layers "F.Cu" "F.Mask" "F.Paste")
			(net "PVCCFA_EHV_FIVRA_CPU0")
		)
		(pad "BJ80" smd circle
			(at 28.472384 -4.408932 270)
			(size 0.4318 0.4318)
			(layers "F.Cu" "F.Mask" "F.Paste")
			(net "GND")
		)
		(pad "BJ82" smd circle
			(at 30.100016 -4.408932 270)
			(size 0.4318 0.4318)
			(layers "F.Cu" "F.Mask" "F.Paste")
			(net "GND")
		)
		(pad "BJ84" smd circle
			(at 31.727902 -4.408932 270)
			(size 0.4318 0.4318)
			(layers "F.Cu" "F.Mask" "F.Paste")
			(net "GND")
		)
		(pad "BJ86" smd circle
			(at 33.355534 -4.408932 270)
			(size 0.4318 0.4318)
			(layers "F.Cu" "F.Mask" "F.Paste")
			(net "GND")
		)
		(pad "BJ88" smd circle
			(at 34.98342 -4.408932 270)
			(size 0.4318 0.4318)
			(layers "F.Cu" "F.Mask" "F.Paste")
			(net "GND")
		)
		(pad "BJ90" smd circle
			(at 36.611306 -4.408932 270)
			(size 0.4318 0.4318)
			(layers "F.Cu" "F.Mask" "F.Paste")
			(net "GND")
		)
		(pad "BK2" smd circle
			(at -36.611306 -4.049268 270)
			(size 0.4318 0.4318)
			(layers "F.Cu" "F.Mask" "F.Paste")
			(net "UPI_CPU0_CPU1_P0P1_DP<20>")
		)
		(pad "BK4" smd circle
			(at -34.98342 -4.049268 270)
			(size 0.4318 0.4318)
			(layers "F.Cu" "F.Mask" "F.Paste")
			(net "GND")
		)
		(pad "BK6" smd circle
			(at -33.355534 -4.049268 270)
			(size 0.4318 0.4318)
			(layers "F.Cu" "F.Mask" "F.Paste")
			(net "UPI_CPU1_CPU0_P1P0_DP<20>")
		)
		(pad "BK8" smd circle
			(at -31.727902 -4.049268 270)
			(size 0.4318 0.4318)
			(layers "F.Cu" "F.Mask" "F.Paste")
			(net "GND")
		)
		(pad "BK10" smd circle
			(at -30.100016 -4.049268 270)
			(size 0.4318 0.4318)
			(layers "F.Cu" "F.Mask" "F.Paste")
			(net "P5E_CPU0_PE1_RX_DN<12>")
		)
		(pad "BK12" smd circle
			(at -28.472384 -4.049268 270)
			(size 0.4318 0.4318)
			(layers "F.Cu" "F.Mask" "F.Paste")
			(net "GND")
		)
		(pad "BK14" smd circle
			(at -26.844498 -4.049268 270)
			(size 0.4318 0.4318)
			(layers "F.Cu" "F.Mask" "F.Paste")
			(net "P5E_CPU0_PE1_TX_DN<12>")
		)
		(pad "BK16" smd circle
			(at -25.216612 -4.049268 270)
			(size 0.4318 0.4318)
			(layers "F.Cu" "F.Mask" "F.Paste")
			(net "GND")
		)
		(pad "BK18" smd circle
			(at -23.58898 -4.049268 270)
			(size 0.4318 0.4318)
			(layers "F.Cu" "F.Mask" "F.Paste")
			(net "DMI_CPU0_PCH_RX_C_DP<4>")
		)
		(pad "BK20" smd circle
			(at -21.961094 -4.049268 270)
			(size 0.4318 0.4318)
			(layers "F.Cu" "F.Mask" "F.Paste")
			(net "GND")
		)
		(pad "BK22" smd circle
			(at -20.333462 -4.049268 270)
			(size 0.4318 0.4318)
			(layers "F.Cu" "F.Mask" "F.Paste")
			(net "NC_CPU0_MDFI_DIE00_NS0")
		)
		(pad "BK24" smd circle
			(at -18.705576 -4.049268 270)
			(size 0.4318 0.4318)
			(layers "F.Cu" "F.Mask" "F.Paste")
			(net "DBP_CPU0_HOOK9_MBP3_GTL_QS_R_N")
		)
		(pad "BK26" smd circle
			(at -17.07769 -4.049268 270)
			(size 0.4318 0.4318)
			(layers "F.Cu" "F.Mask" "F.Paste")
			(net "SVID_ALERT0_CPU0_N")
		)
		(pad "BK61" smd circle
			(at 13.008356 -3.939286 270)
			(size 0.4318 0.4318)
			(layers "F.Cu" "F.Mask" "F.Paste")
			(net "PVCCINFAON_CPU0")
		)
		(pad "BK63" smd circle
			(at 14.635988 -3.939286 270)
			(size 0.4318 0.4318)
			(layers "F.Cu" "F.Mask" "F.Paste")
			(net "TP_ESPI_IBL_CPU0_IO0_LVC1")
		)
		(pad "BK65" smd circle
			(at 16.263874 -3.939286 270)
			(size 0.4318 0.4318)
			(layers "F.Cu" "F.Mask" "F.Paste")
			(net "GND")
		)
		(pad "BK67" smd circle
			(at 17.89176 -3.939286 270)
			(size 0.4318 0.4318)
			(layers "F.Cu" "F.Mask" "F.Paste")
			(net "TP_TRC_CPU0_PTI3_CLK")
		)
		(pad "BK69" smd circle
			(at 19.519392 -3.939286 270)
			(size 0.4318 0.4318)
			(layers "F.Cu" "F.Mask" "F.Paste")
			(net "TP_TRC_CPU0_PTI<24>")
		)
		(pad "BK71" smd circle
			(at 21.147278 -3.939286 270)
			(size 0.4318 0.4318)
			(layers "F.Cu" "F.Mask" "F.Paste")
			(net "GND")
		)
		(pad "BK73" smd circle
			(at 22.77491 -3.939286 270)
			(size 0.4318 0.4318)
			(layers "F.Cu" "F.Mask" "F.Paste")
			(net "UPI_CPU1_CPU0_P2P2_DN<1>")
		)
		(pad "BK75" smd circle
			(at 24.402796 -3.939286 270)
			(size 0.4318 0.4318)
			(layers "F.Cu" "F.Mask" "F.Paste")
			(net "GND")
		)
		(pad "BK77" smd circle
			(at 26.030682 -3.939286 270)
			(size 0.4318 0.4318)
			(layers "F.Cu" "F.Mask" "F.Paste")
			(net "UPI_CPU1_CPU0_P2P2_DP<5>")
		)
		(pad "BK79" smd circle
			(at 27.658314 -3.939286 270)
			(size 0.4318 0.4318)
			(layers "F.Cu" "F.Mask" "F.Paste")
			(net "GND")
		)
		(pad "BK81" smd circle
			(at 29.2862 -3.939286 270)
			(size 0.4318 0.4318)
			(layers "F.Cu" "F.Mask" "F.Paste")
			(net "PVCCIN_CPU0")
		)
		(pad "BK83" smd circle
			(at 30.914086 -3.939286 270)
			(size 0.4318 0.4318)
			(layers "F.Cu" "F.Mask" "F.Paste")
			(net "PVCCIN_CPU0")
		)
		(pad "BK85" smd circle
			(at 32.541718 -3.939286 270)
			(size 0.4318 0.4318)
			(layers "F.Cu" "F.Mask" "F.Paste")
			(net "PVCCIN_CPU0")
		)
		(pad "BK87" smd circle
			(at 34.169604 -3.939286 270)
			(size 0.4318 0.4318)
			(layers "F.Cu" "F.Mask" "F.Paste")
			(net "PVCCIN_CPU0")
		)
		(pad "BK89" smd circle
			(at 35.797236 -3.939286 270)
			(size 0.4318 0.4318)
			(layers "F.Cu" "F.Mask" "F.Paste")
			(net "PVCCIN_CPU0")
		)
		(pad "BK91" smd oval
			(at 37.425122 -3.939286)
			(size 0.381 0.4826)
			(drill
				(offset 0 -0.0508)
			)
			(layers "F.Cu" "F.Mask" "F.Paste")
			(net "PVCCIN_CPU0")
		)
		(pad "BL1" smd oval
			(at -37.425122 -3.579114 180)
			(size 0.381 0.4826)
			(drill
				(offset 0 -0.0508)
			)
			(layers "F.Cu" "F.Mask" "F.Paste")
			(net "GND")
		)
		(pad "BL3" smd circle
			(at -35.797236 -3.579114 270)
			(size 0.4318 0.4318)
			(layers "F.Cu" "F.Mask" "F.Paste")
			(net "UPI_CPU0_CPU1_P0P1_DN<21>")
		)
		(pad "BL5" smd circle
			(at -34.169604 -3.579114 270)
			(size 0.4318 0.4318)
			(layers "F.Cu" "F.Mask" "F.Paste")
			(net "GND")
		)
		(pad "BL7" smd circle
			(at -32.541718 -3.579114 270)
			(size 0.4318 0.4318)
			(layers "F.Cu" "F.Mask" "F.Paste")
			(net "UPI_CPU1_CPU0_P1P0_DN<20>")
		)
		(pad "BL9" smd circle
			(at -30.914086 -3.579114 270)
			(size 0.4318 0.4318)
			(layers "F.Cu" "F.Mask" "F.Paste")
			(net "GND")
		)
		(pad "BL11" smd circle
			(at -29.2862 -3.579114 270)
			(size 0.4318 0.4318)
			(layers "F.Cu" "F.Mask" "F.Paste")
			(net "P5E_CPU0_PE1_RX_DN<11>")
		)
		(pad "BL13" smd circle
			(at -27.658314 -3.579114 270)
			(size 0.4318 0.4318)
			(layers "F.Cu" "F.Mask" "F.Paste")
			(net "GND")
		)
		(pad "BL15" smd circle
			(at -26.030682 -3.579114 270)
			(size 0.4318 0.4318)
			(layers "F.Cu" "F.Mask" "F.Paste")
			(net "P5E_CPU0_PE1_TX_DP<12>")
		)
		(pad "BL17" smd circle
			(at -24.402796 -3.579114 270)
			(size 0.4318 0.4318)
			(layers "F.Cu" "F.Mask" "F.Paste")
			(net "GND")
		)
		(pad "BL19" smd circle
			(at -22.77491 -3.579114 270)
			(size 0.4318 0.4318)
			(layers "F.Cu" "F.Mask" "F.Paste")
			(net "DMI_CPU0_PCH_RX_C_DN<4>")
		)
		(pad "BL21" smd circle
			(at -21.147278 -3.579114 270)
			(size 0.4318 0.4318)
			(layers "F.Cu" "F.Mask" "F.Paste")
			(net "NC_CPU0_PE0_APROBE<1>")
		)
		(pad "BL23" smd circle
			(at -19.519392 -3.579114 270)
			(size 0.4318 0.4318)
			(layers "F.Cu" "F.Mask" "F.Paste")
			(net "DBP_CPU0_MBP0_GTL_R_N")
		)
		(pad "BL25" smd circle
			(at -17.89176 -3.579114 270)
			(size 0.4318 0.4318)
			(layers "F.Cu" "F.Mask" "F.Paste")
			(net "SVID_DIO1_CPU0")
		)
		(pad "BL60" smd circle
			(at 12.19454 -3.469132 270)
			(size 0.4318 0.4318)
			(layers "F.Cu" "F.Mask" "F.Paste")
			(net "NC_CPU0_HBM3_VIEWDIG1")
		)
		(pad "BL62" smd circle
			(at 13.822426 -3.469132 270)
			(size 0.4318 0.4318)
			(layers "F.Cu" "F.Mask" "F.Paste")
			(net "H_CPU0_THERMTRIP_LVC1_R_N")
		)
		(pad "BL64" smd circle
			(at 15.450058 -3.469132 270)
			(size 0.4318 0.4318)
			(layers "F.Cu" "F.Mask" "F.Paste")
			(net "FM_CPU0_PKGID0")
		)
		(pad "BL66" smd circle
			(at 17.07769 -3.469132 270)
			(size 0.4318 0.4318)
			(layers "F.Cu" "F.Mask" "F.Paste")
			(net "TP_TRC_CPU0_PTI<29>")
		)
		(pad "BL68" smd circle
			(at 18.705576 -3.469132 270)
			(size 0.4318 0.4318)
			(layers "F.Cu" "F.Mask" "F.Paste")
			(net "GND")
		)
		(pad "BL70" smd circle
			(at 20.333462 -3.469132 270)
			(size 0.4318 0.4318)
			(layers "F.Cu" "F.Mask" "F.Paste")
			(net "GND")
		)
		(pad "BL72" smd circle
			(at 21.961094 -3.469132 270)
			(size 0.4318 0.4318)
			(layers "F.Cu" "F.Mask" "F.Paste")
			(net "GND")
		)
		(pad "BL74" smd circle
			(at 23.58898 -3.469132 270)
			(size 0.4318 0.4318)
			(layers "F.Cu" "F.Mask" "F.Paste")
			(net "UPI_CPU1_CPU0_P2P2_DP<1>")
		)
		(pad "BL76" smd circle
			(at 25.216612 -3.469132 270)
			(size 0.4318 0.4318)
			(layers "F.Cu" "F.Mask" "F.Paste")
			(net "UPI_CPU1_CPU0_P2P2_DP<4>")
		)
		(pad "BL78" smd circle
			(at 26.844498 -3.469132 270)
			(size 0.4318 0.4318)
			(layers "F.Cu" "F.Mask" "F.Paste")
			(net "GND")
		)
		(pad "BL80" smd circle
			(at 28.472384 -3.469132 270)
			(size 0.4318 0.4318)
			(layers "F.Cu" "F.Mask" "F.Paste")
			(net "PVCCIN_CPU0")
		)
		(pad "BL82" smd circle
			(at 30.100016 -3.469132 270)
			(size 0.4318 0.4318)
			(layers "F.Cu" "F.Mask" "F.Paste")
			(net "PVCCIN_CPU0")
		)
		(pad "BL84" smd circle
			(at 31.727902 -3.469132 270)
			(size 0.4318 0.4318)
			(layers "F.Cu" "F.Mask" "F.Paste")
			(net "PVCCIN_CPU0")
		)
		(pad "BL86" smd circle
			(at 33.355534 -3.469132 270)
			(size 0.4318 0.4318)
			(layers "F.Cu" "F.Mask" "F.Paste")
			(net "PVCCIN_CPU0")
		)
		(pad "BL88" smd circle
			(at 34.98342 -3.469132 270)
			(size 0.4318 0.4318)
			(layers "F.Cu" "F.Mask" "F.Paste")
			(net "PVCCIN_CPU0")
		)
		(pad "BL90" smd circle
			(at 36.611306 -3.469132 270)
			(size 0.4318 0.4318)
			(layers "F.Cu" "F.Mask" "F.Paste")
			(net "PVCCIN_CPU0")
		)
		(pad "BM2" smd oval
			(at -36.611306 -3.109468 180)
			(size 0.381 0.4826)
			(drill
				(offset 0 -0.0508)
			)
			(layers "F.Cu" "F.Mask" "F.Paste")
			(net "UPI_CPU0_CPU1_P0P1_DP<21>")
		)
		(pad "BM4" smd circle
			(at -34.98342 -3.109468 270)
			(size 0.4318 0.4318)
			(layers "F.Cu" "F.Mask" "F.Paste")
			(net "GND")
		)
		(pad "BM6" smd circle
			(at -33.355534 -3.109468 270)
			(size 0.4318 0.4318)
			(layers "F.Cu" "F.Mask" "F.Paste")
			(net "UPI_CPU1_CPU0_P1P0_DN<21>")
		)
		(pad "BM8" smd circle
			(at -31.727902 -3.109468 270)
			(size 0.4318 0.4318)
			(layers "F.Cu" "F.Mask" "F.Paste")
			(net "GND")
		)
		(pad "BM10" smd circle
			(at -30.100016 -3.109468 270)
			(size 0.4318 0.4318)
			(layers "F.Cu" "F.Mask" "F.Paste")
			(net "P5E_CPU0_PE1_RX_DP<11>")
		)
		(pad "BM12" smd circle
			(at -28.472384 -3.109468 270)
			(size 0.4318 0.4318)
			(layers "F.Cu" "F.Mask" "F.Paste")
			(net "GND")
		)
		(pad "BM14" smd circle
			(at -26.844498 -3.109468 270)
			(size 0.4318 0.4318)
			(layers "F.Cu" "F.Mask" "F.Paste")
			(net "P5E_CPU0_PE1_TX_DP<11>")
		)
		(pad "BM16" smd circle
			(at -25.216612 -3.109468 270)
			(size 0.4318 0.4318)
			(layers "F.Cu" "F.Mask" "F.Paste")
			(net "GND")
		)
		(pad "BM18" smd circle
			(at -23.58898 -3.109468 270)
			(size 0.4318 0.4318)
			(layers "F.Cu" "F.Mask" "F.Paste")
			(net "DMI_CPU0_PCH_RX_C_DN<5>")
		)
		(pad "BM20" smd circle
			(at -21.961094 -3.109468 270)
			(size 0.4318 0.4318)
			(layers "F.Cu" "F.Mask" "F.Paste")
			(net "GND")
		)
		(pad "BM22" smd circle
			(at -20.333462 -3.109468 270)
			(size 0.4318 0.4318)
			(layers "F.Cu" "F.Mask" "F.Paste")
			(net "GND")
		)
		(pad "BM24" smd circle
			(at -18.705576 -3.109468 270)
			(size 0.4318 0.4318)
			(layers "F.Cu" "F.Mask" "F.Paste")
			(net "GND")
		)
		(pad "BM26" smd circle
			(at -17.07769 -3.109468 270)
			(size 0.4318 0.4318)
			(layers "F.Cu" "F.Mask" "F.Paste")
			(net "GND")
		)
		(pad "BM61" smd circle
			(at 13.008356 -2.999486 270)
			(size 0.4318 0.4318)
			(layers "F.Cu" "F.Mask" "F.Paste")
			(net "GND")
		)
		(pad "BM63" smd circle
			(at 14.635988 -2.999486 270)
			(size 0.4318 0.4318)
			(layers "F.Cu" "F.Mask" "F.Paste")
			(net "TP_ESPI_IBL_CPU0_IO3_LVC1")
		)
		(pad "BM65" smd circle
			(at 16.263874 -2.999486 270)
			(size 0.4318 0.4318)
			(layers "F.Cu" "F.Mask" "F.Paste")
			(net "NC_CPU0_SOC_SPARE1")
		)
		(pad "BM67" smd circle
			(at 17.89176 -2.999486 270)
			(size 0.4318 0.4318)
			(layers "F.Cu" "F.Mask" "F.Paste")
			(net "TP_TRC_CPU0_PTI<30>")
		)
		(pad "BM69" smd circle
			(at 19.519392 -2.999486 270)
			(size 0.4318 0.4318)
			(layers "F.Cu" "F.Mask" "F.Paste")
			(net "TP_TRC_CPU0_PTI<25>")
		)
		(pad "BM71" smd circle
			(at 21.147278 -2.999486 270)
			(size 0.4318 0.4318)
			(layers "F.Cu" "F.Mask" "F.Paste")
			(net "UPI_CPU0_CPU1_P2P2_DN<0>")
		)
		(pad "BM73" smd circle
			(at 22.77491 -2.999486 270)
			(size 0.4318 0.4318)
			(layers "F.Cu" "F.Mask" "F.Paste")
			(net "GND")
		)
		(pad "BM75" smd circle
			(at 24.402796 -2.999486 270)
			(size 0.4318 0.4318)
			(layers "F.Cu" "F.Mask" "F.Paste")
			(net "UPI_CPU1_CPU0_P2P2_DN<2>")
		)
	)
)
